(kicad_sch (version 20230121) (generator eeschema)

  (paper "A3")

  (title_block
    (title "Data Center RDIMM DDR4 Tester")
    (date "2024-09-30")
    (rev "1.2.4")
    (comment 1 "www.antmicro.com")
    (comment 2 "Antmicro Ltd")
  )


  (wire (pts (xy 226.695 53.34) (xy 229.87 53.34))
    (stroke (width 0) (type default))
  )
  (wire (pts (xy 226.695 76.2) (xy 229.235 76.2))
    (stroke (width 0) (type default))
  )
  (wire (pts (xy 169.545 93.98) (xy 172.085 93.98))
    (stroke (width 0) (type default))
  )
  (wire (pts (xy 169.545 71.12) (xy 172.085 71.12))
    (stroke (width 0) (type default))
  )
  (wire (pts (xy 169.545 78.74) (xy 172.085 78.74))
    (stroke (width 0) (type default))
  )
  (wire (pts (xy 169.545 66.04) (xy 172.085 66.04))
    (stroke (width 0) (type default))
  )
  (wire (pts (xy 149.86 104.14) (xy 172.085 104.14))
    (stroke (width 0) (type default))
  )
  (wire (pts (xy 137.16 101.6) (xy 172.085 101.6))
    (stroke (width 0) (type default))
  )
  (wire (pts (xy 254.635 99.06) (xy 272.415 99.06))
    (stroke (width 0) (type default))
  )
  (wire (pts (xy 149.86 99.06) (xy 172.085 99.06))
    (stroke (width 0) (type default))
  )
  (wire (pts (xy 169.545 68.58) (xy 172.085 68.58))
    (stroke (width 0) (type default))
  )
  (wire (pts (xy 169.545 81.28) (xy 172.085 81.28))
    (stroke (width 0) (type default))
  )
  (wire (pts (xy 169.545 60.96) (xy 172.085 60.96))
    (stroke (width 0) (type default))
  )
  (wire (pts (xy 226.695 78.74) (xy 229.235 78.74))
    (stroke (width 0) (type default))
  )
  (wire (pts (xy 267.335 106.68) (xy 272.415 106.68))
    (stroke (width 0) (type default))
  )
  (wire (pts (xy 226.695 86.36) (xy 229.235 86.36))
    (stroke (width 0) (type default))
  )
  (wire (pts (xy 137.16 106.68) (xy 172.085 106.68))
    (stroke (width 0) (type default))
  )
  (wire (pts (xy 169.545 53.34) (xy 172.085 53.34))
    (stroke (width 0) (type default))
  )
  (wire (pts (xy 226.695 68.58) (xy 229.87 68.58))
    (stroke (width 0) (type default))
  )
  (wire (pts (xy 169.545 83.82) (xy 172.085 83.82))
    (stroke (width 0) (type default))
  )
  (wire (pts (xy 226.695 91.44) (xy 229.235 91.44))
    (stroke (width 0) (type default))
  )
  (wire (pts (xy 226.695 104.14) (xy 249.555 104.14))
    (stroke (width 0) (type default))
  )
  (wire (pts (xy 226.695 106.68) (xy 262.255 106.68))
    (stroke (width 0) (type default))
  )
  (wire (pts (xy 226.695 81.28) (xy 229.235 81.28))
    (stroke (width 0) (type default))
  )
  (wire (pts (xy 267.335 101.6) (xy 272.415 101.6))
    (stroke (width 0) (type default))
  )
  (wire (pts (xy 226.695 66.04) (xy 229.87 66.04))
    (stroke (width 0) (type default))
  )
  (wire (pts (xy 226.695 55.88) (xy 229.87 55.88))
    (stroke (width 0) (type default))
  )
  (wire (pts (xy 226.695 58.42) (xy 229.87 58.42))
    (stroke (width 0) (type default))
  )
  (wire (pts (xy 226.695 101.6) (xy 262.255 101.6))
    (stroke (width 0) (type default))
  )
  (wire (pts (xy 226.695 60.96) (xy 229.87 60.96))
    (stroke (width 0) (type default))
  )
  (wire (pts (xy 226.695 93.98) (xy 229.235 93.98))
    (stroke (width 0) (type default))
  )
  (wire (pts (xy 126.365 99.06) (xy 144.78 99.06))
    (stroke (width 0) (type default))
  )
  (wire (pts (xy 226.695 63.5) (xy 229.87 63.5))
    (stroke (width 0) (type default))
  )
  (wire (pts (xy 226.695 99.06) (xy 249.555 99.06))
    (stroke (width 0) (type default))
  )
  (wire (pts (xy 254.635 104.14) (xy 272.415 104.14))
    (stroke (width 0) (type default))
  )
  (wire (pts (xy 226.695 71.12) (xy 229.87 71.12))
    (stroke (width 0) (type default))
  )
  (wire (pts (xy 126.365 106.68) (xy 132.08 106.68))
    (stroke (width 0) (type default))
  )
  (wire (pts (xy 169.545 88.9) (xy 172.085 88.9))
    (stroke (width 0) (type default))
  )
  (wire (pts (xy 169.545 86.36) (xy 172.085 86.36))
    (stroke (width 0) (type default))
  )
  (wire (pts (xy 169.545 58.42) (xy 172.085 58.42))
    (stroke (width 0) (type default))
  )
  (wire (pts (xy 226.695 88.9) (xy 229.235 88.9))
    (stroke (width 0) (type default))
  )
  (wire (pts (xy 169.545 91.44) (xy 172.085 91.44))
    (stroke (width 0) (type default))
  )
  (wire (pts (xy 169.545 55.88) (xy 172.085 55.88))
    (stroke (width 0) (type default))
  )
  (wire (pts (xy 226.695 83.82) (xy 229.235 83.82))
    (stroke (width 0) (type default))
  )
  (wire (pts (xy 126.365 104.14) (xy 144.78 104.14))
    (stroke (width 0) (type default))
  )
  (wire (pts (xy 126.365 101.6) (xy 132.08 101.6))
    (stroke (width 0) (type default))
  )
  (wire (pts (xy 169.545 76.2) (xy 172.085 76.2))
    (stroke (width 0) (type default))
  )
  (wire (pts (xy 169.545 63.5) (xy 172.085 63.5))
    (stroke (width 0) (type default))
  )

  (text "BANK 115" (at 147.955 44.45 0)
    (effects (font (size 2.4892 2.4892) (thickness 0.4978) bold) (justify left bottom))
  )
  (text "BANK 115" (at 233.045 44.45 0)
    (effects (font (size 2.4892 2.4892) (thickness 0.4978) bold) (justify left bottom))
  )

  (label "GTR_REFCLK3_P" (at 243.205 104.14 180) (fields_autoplaced)
    (effects (font (size 1.27 1.27)) (justify right bottom))
  )
  (label "GTR_REFCLK3_N" (at 243.205 106.68 180) (fields_autoplaced)
    (effects (font (size 1.27 1.27)) (justify right bottom))
  )
  (label "GTR_REFCLK2_N" (at 243.205 101.6 180) (fields_autoplaced)
    (effects (font (size 1.27 1.27)) (justify right bottom))
  )
  (label "GTR_REFCLK1_N" (at 155.575 106.68 0) (fields_autoplaced)
    (effects (font (size 1.27 1.27)) (justify left bottom))
  )
  (label "GTR_REFCLK0_P" (at 155.575 99.06 0) (fields_autoplaced)
    (effects (font (size 1.27 1.27)) (justify left bottom))
  )
  (label "GTR_REFCLK1_P" (at 155.575 104.14 0) (fields_autoplaced)
    (effects (font (size 1.27 1.27)) (justify left bottom))
  )
  (label "GTR_REFCLK2_P" (at 243.205 99.06 180) (fields_autoplaced)
    (effects (font (size 1.27 1.27)) (justify right bottom))
  )
  (label "GTR_REFCLK0_N" (at 155.575 101.6 0) (fields_autoplaced)
    (effects (font (size 1.27 1.27)) (justify left bottom))
  )

  (global_label "GTX_TX2_P" (shape input) (at 229.87 58.42 0) (fields_autoplaced)
    (effects (font (size 1.27 1.27)) (justify left))
    (property "Intersheetrefs" "${INTERSHEET_REFS}" (at 242.2332 58.3406 0)
      (effects (font (size 1.27 1.27)) (justify left) hide)
    )
  )
  (global_label "GTX_TX5_P" (shape input) (at 169.545 63.5 180) (fields_autoplaced)
    (effects (font (size 1.27 1.27)) (justify right))
    (property "Intersheetrefs" "${INTERSHEET_REFS}" (at 157.1818 63.4206 0)
      (effects (font (size 1.27 1.27)) (justify right) hide)
    )
  )
  (global_label "GTR_REFCLK0_C_N" (shape input) (at 126.365 101.6 180) (fields_autoplaced)
    (effects (font (size 1.27 1.27)) (justify right))
    (property "Intersheetrefs" "${INTERSHEET_REFS}" (at 106.7446 101.6794 0)
      (effects (font (size 1.27 1.27)) (justify right) hide)
    )
  )
  (global_label "GTX_TX4_N" (shape input) (at 169.545 71.12 180) (fields_autoplaced)
    (effects (font (size 1.27 1.27)) (justify right))
    (property "Intersheetrefs" "${INTERSHEET_REFS}" (at 157.1213 71.0406 0)
      (effects (font (size 1.27 1.27)) (justify right) hide)
    )
  )
  (global_label "GTR_REFCLK2_C_P" (shape input) (at 272.415 99.06 0) (fields_autoplaced)
    (effects (font (size 1.27 1.27)) (justify left))
    (property "Intersheetrefs" "${INTERSHEET_REFS}" (at 291.9749 98.9806 0)
      (effects (font (size 1.27 1.27)) (justify left) hide)
    )
  )
  (global_label "GTX_TX5_N" (shape input) (at 169.545 66.04 180) (fields_autoplaced)
    (effects (font (size 1.27 1.27)) (justify right))
    (property "Intersheetrefs" "${INTERSHEET_REFS}" (at 157.1213 65.9606 0)
      (effects (font (size 1.27 1.27)) (justify right) hide)
    )
  )
  (global_label "GTX_RX7_P" (shape input) (at 169.545 76.2 180) (fields_autoplaced)
    (effects (font (size 1.27 1.27)) (justify right))
    (property "Intersheetrefs" "${INTERSHEET_REFS}" (at 156.8794 76.1206 0)
      (effects (font (size 1.27 1.27)) (justify right) hide)
    )
  )
  (global_label "GTX_TX4_P" (shape input) (at 169.545 68.58 180) (fields_autoplaced)
    (effects (font (size 1.27 1.27)) (justify right))
    (property "Intersheetrefs" "${INTERSHEET_REFS}" (at 157.1818 68.5006 0)
      (effects (font (size 1.27 1.27)) (justify right) hide)
    )
  )
  (global_label "GTX_RX1_P" (shape input) (at 229.235 86.36 0) (fields_autoplaced)
    (effects (font (size 1.27 1.27)) (justify left))
    (property "Intersheetrefs" "${INTERSHEET_REFS}" (at 241.9006 86.2806 0)
      (effects (font (size 1.27 1.27)) (justify left) hide)
    )
  )
  (global_label "GTX_RX1_N" (shape input) (at 229.235 88.9 0) (fields_autoplaced)
    (effects (font (size 1.27 1.27)) (justify left))
    (property "Intersheetrefs" "${INTERSHEET_REFS}" (at 241.9611 88.8206 0)
      (effects (font (size 1.27 1.27)) (justify left) hide)
    )
  )
  (global_label "GTX_RX3_P" (shape input) (at 229.235 76.2 0) (fields_autoplaced)
    (effects (font (size 1.27 1.27)) (justify left))
    (property "Intersheetrefs" "${INTERSHEET_REFS}" (at 241.9006 76.1206 0)
      (effects (font (size 1.27 1.27)) (justify left) hide)
    )
  )
  (global_label "GTR_REFCLK3_C_P" (shape input) (at 272.415 104.14 0) (fields_autoplaced)
    (effects (font (size 1.27 1.27)) (justify left))
    (property "Intersheetrefs" "${INTERSHEET_REFS}" (at 291.9749 104.0606 0)
      (effects (font (size 1.27 1.27)) (justify left) hide)
    )
  )
  (global_label "GTX_TX7_N" (shape input) (at 169.545 55.88 180) (fields_autoplaced)
    (effects (font (size 1.27 1.27)) (justify right))
    (property "Intersheetrefs" "${INTERSHEET_REFS}" (at 157.1213 55.8006 0)
      (effects (font (size 1.27 1.27)) (justify right) hide)
    )
  )
  (global_label "GTX_RX0_N" (shape input) (at 229.235 93.98 0) (fields_autoplaced)
    (effects (font (size 1.27 1.27)) (justify left))
    (property "Intersheetrefs" "${INTERSHEET_REFS}" (at 241.9611 93.9006 0)
      (effects (font (size 1.27 1.27)) (justify left) hide)
    )
  )
  (global_label "GTX_RX5_P" (shape input) (at 169.545 86.36 180) (fields_autoplaced)
    (effects (font (size 1.27 1.27)) (justify right))
    (property "Intersheetrefs" "${INTERSHEET_REFS}" (at 156.8794 86.2806 0)
      (effects (font (size 1.27 1.27)) (justify right) hide)
    )
  )
  (global_label "GTR_REFCLK1_C_N" (shape input) (at 126.365 106.68 180) (fields_autoplaced)
    (effects (font (size 1.27 1.27)) (justify right))
    (property "Intersheetrefs" "${INTERSHEET_REFS}" (at 106.7446 106.6006 0)
      (effects (font (size 1.27 1.27)) (justify right) hide)
    )
  )
  (global_label "GTR_REFCLK2_C_N" (shape input) (at 272.415 101.6 0) (fields_autoplaced)
    (effects (font (size 1.27 1.27)) (justify left))
    (property "Intersheetrefs" "${INTERSHEET_REFS}" (at 292.0354 101.5206 0)
      (effects (font (size 1.27 1.27)) (justify left) hide)
    )
  )
  (global_label "GTR_REFCLK1_C_P" (shape input) (at 126.365 104.14 180) (fields_autoplaced)
    (effects (font (size 1.27 1.27)) (justify right))
    (property "Intersheetrefs" "${INTERSHEET_REFS}" (at 106.8051 104.0606 0)
      (effects (font (size 1.27 1.27)) (justify right) hide)
    )
  )
  (global_label "GTR_REFCLK0_C_P" (shape input) (at 126.365 99.06 180) (fields_autoplaced)
    (effects (font (size 1.27 1.27)) (justify right))
    (property "Intersheetrefs" "${INTERSHEET_REFS}" (at 106.8051 99.1394 0)
      (effects (font (size 1.27 1.27)) (justify right) hide)
    )
  )
  (global_label "GTX_TX6_P" (shape input) (at 169.545 58.42 180) (fields_autoplaced)
    (effects (font (size 1.27 1.27)) (justify right))
    (property "Intersheetrefs" "${INTERSHEET_REFS}" (at 157.1818 58.3406 0)
      (effects (font (size 1.27 1.27)) (justify right) hide)
    )
  )
  (global_label "GTX_RX4_N" (shape input) (at 169.545 93.98 180) (fields_autoplaced)
    (effects (font (size 1.27 1.27)) (justify right))
    (property "Intersheetrefs" "${INTERSHEET_REFS}" (at 156.8189 93.9006 0)
      (effects (font (size 1.27 1.27)) (justify right) hide)
    )
  )
  (global_label "GTX_RX5_N" (shape input) (at 169.545 88.9 180) (fields_autoplaced)
    (effects (font (size 1.27 1.27)) (justify right))
    (property "Intersheetrefs" "${INTERSHEET_REFS}" (at 156.8189 88.8206 0)
      (effects (font (size 1.27 1.27)) (justify right) hide)
    )
  )
  (global_label "GTX_RX2_N" (shape input) (at 229.235 83.82 0) (fields_autoplaced)
    (effects (font (size 1.27 1.27)) (justify left))
    (property "Intersheetrefs" "${INTERSHEET_REFS}" (at 241.9611 83.7406 0)
      (effects (font (size 1.27 1.27)) (justify left) hide)
    )
  )
  (global_label "GTX_TX7_P" (shape input) (at 169.545 53.34 180) (fields_autoplaced)
    (effects (font (size 1.27 1.27)) (justify right))
    (property "Intersheetrefs" "${INTERSHEET_REFS}" (at 157.1818 53.2606 0)
      (effects (font (size 1.27 1.27)) (justify right) hide)
    )
  )
  (global_label "GTX_TX1_N" (shape input) (at 229.87 66.04 0) (fields_autoplaced)
    (effects (font (size 1.27 1.27)) (justify left))
    (property "Intersheetrefs" "${INTERSHEET_REFS}" (at 242.2937 65.9606 0)
      (effects (font (size 1.27 1.27)) (justify left) hide)
    )
  )
  (global_label "GTX_RX4_P" (shape input) (at 169.545 91.44 180) (fields_autoplaced)
    (effects (font (size 1.27 1.27)) (justify right))
    (property "Intersheetrefs" "${INTERSHEET_REFS}" (at 156.8794 91.3606 0)
      (effects (font (size 1.27 1.27)) (justify right) hide)
    )
  )
  (global_label "GTX_RX3_N" (shape input) (at 229.235 78.74 0) (fields_autoplaced)
    (effects (font (size 1.27 1.27)) (justify left))
    (property "Intersheetrefs" "${INTERSHEET_REFS}" (at 241.9611 78.6606 0)
      (effects (font (size 1.27 1.27)) (justify left) hide)
    )
  )
  (global_label "GTX_TX0_P" (shape input) (at 229.87 68.58 0) (fields_autoplaced)
    (effects (font (size 1.27 1.27)) (justify left))
    (property "Intersheetrefs" "${INTERSHEET_REFS}" (at 242.2332 68.6594 0)
      (effects (font (size 1.27 1.27)) (justify left) hide)
    )
  )
  (global_label "GTX_RX2_P" (shape input) (at 229.235 81.28 0) (fields_autoplaced)
    (effects (font (size 1.27 1.27)) (justify left))
    (property "Intersheetrefs" "${INTERSHEET_REFS}" (at 241.9006 81.2006 0)
      (effects (font (size 1.27 1.27)) (justify left) hide)
    )
  )
  (global_label "GTX_TX3_N" (shape input) (at 229.87 55.88 0) (fields_autoplaced)
    (effects (font (size 1.27 1.27)) (justify left))
    (property "Intersheetrefs" "${INTERSHEET_REFS}" (at 242.2937 55.8006 0)
      (effects (font (size 1.27 1.27)) (justify left) hide)
    )
  )
  (global_label "GTX_RX0_P" (shape input) (at 229.235 91.44 0) (fields_autoplaced)
    (effects (font (size 1.27 1.27)) (justify left))
    (property "Intersheetrefs" "${INTERSHEET_REFS}" (at 241.9006 91.3606 0)
      (effects (font (size 1.27 1.27)) (justify left) hide)
    )
  )
  (global_label "GTX_TX3_P" (shape input) (at 229.87 53.34 0) (fields_autoplaced)
    (effects (font (size 1.27 1.27)) (justify left))
    (property "Intersheetrefs" "${INTERSHEET_REFS}" (at 242.2332 53.2606 0)
      (effects (font (size 1.27 1.27)) (justify left) hide)
    )
  )
  (global_label "GTX_TX0_N" (shape input) (at 229.87 71.12 0) (fields_autoplaced)
    (effects (font (size 1.27 1.27)) (justify left))
    (property "Intersheetrefs" "${INTERSHEET_REFS}" (at 242.2937 71.1994 0)
      (effects (font (size 1.27 1.27)) (justify left) hide)
    )
  )
  (global_label "GTX_TX1_P" (shape input) (at 229.87 63.5 0) (fields_autoplaced)
    (effects (font (size 1.27 1.27)) (justify left))
    (property "Intersheetrefs" "${INTERSHEET_REFS}" (at 242.2332 63.4206 0)
      (effects (font (size 1.27 1.27)) (justify left) hide)
    )
  )
  (global_label "GTX_TX2_N" (shape input) (at 229.87 60.96 0) (fields_autoplaced)
    (effects (font (size 1.27 1.27)) (justify left))
    (property "Intersheetrefs" "${INTERSHEET_REFS}" (at 242.2937 60.8806 0)
      (effects (font (size 1.27 1.27)) (justify left) hide)
    )
  )
  (global_label "GTX_TX6_N" (shape input) (at 169.545 60.96 180) (fields_autoplaced)
    (effects (font (size 1.27 1.27)) (justify right))
    (property "Intersheetrefs" "${INTERSHEET_REFS}" (at 157.1213 60.8806 0)
      (effects (font (size 1.27 1.27)) (justify right) hide)
    )
  )
  (global_label "GTR_REFCLK3_C_N" (shape input) (at 272.415 106.68 0) (fields_autoplaced)
    (effects (font (size 1.27 1.27)) (justify left))
    (property "Intersheetrefs" "${INTERSHEET_REFS}" (at 292.0354 106.6006 0)
      (effects (font (size 1.27 1.27)) (justify left) hide)
    )
  )
  (global_label "GTX_RX6_N" (shape input) (at 169.545 83.82 180) (fields_autoplaced)
    (effects (font (size 1.27 1.27)) (justify right))
    (property "Intersheetrefs" "${INTERSHEET_REFS}" (at 156.8189 83.7406 0)
      (effects (font (size 1.27 1.27)) (justify right) hide)
    )
  )
  (global_label "GTX_RX7_N" (shape input) (at 169.545 78.74 180) (fields_autoplaced)
    (effects (font (size 1.27 1.27)) (justify right))
    (property "Intersheetrefs" "${INTERSHEET_REFS}" (at 156.8189 78.6606 0)
      (effects (font (size 1.27 1.27)) (justify right) hide)
    )
  )
  (global_label "GTX_RX6_P" (shape input) (at 169.545 81.28 180) (fields_autoplaced)
    (effects (font (size 1.27 1.27)) (justify right))
    (property "Intersheetrefs" "${INTERSHEET_REFS}" (at 156.8794 81.2006 0)
      (effects (font (size 1.27 1.27)) (justify right) hide)
    )
  )

  (symbol (lib_id "antmicroCapacitors0402:C_100n_0402") (at 144.78 99.06 0) (unit 1)
    (in_bom yes) (on_board yes) (dnp no)
    (property "Reference" "C246" (at 143.51 97.79 0)
      (effects (font (size 1.524 1.524)))
    )
    (property "Value" "C_100n_0402" (at 165.1 109.22 0)
      (effects (font (size 1.27 1.27) (thickness 0.15)) (justify left bottom) hide)
    )
    (property "Footprint" "antmicro-footprints:C_0402_1005Metric" (at 165.1 111.76 0)
      (effects (font (size 1.27 1.27) (thickness 0.15)) (justify left bottom) hide)
    )
    (property "Datasheet" "https://search.murata.co.jp/Ceramy/image/img/A01X/G101/ENG/GRM155R61H104KE14-01.pdf" (at 165.1 114.3 0)
      (effects (font (size 1.27 1.27) (thickness 0.15)) (justify left bottom) hide)
    )
    (property "Manufacturer" "Murata" (at 165.1 119.38 0)
      (effects (font (size 1.27 1.27) (thickness 0.15)) (justify left bottom) hide)
    )
    (property "MPN" "GRM155R61H104KE14D" (at 165.1 116.84 0)
      (effects (font (size 1.27 1.27) (thickness 0.15)) (justify left bottom) hide)
    )
    (property "Val" "100n" (at 150.495 97.79 0)
      (effects (font (size 1.27 1.27) (thickness 0.15)))
    )
    (property "License" "Apache-2.0" (at 165.1 121.92 0)
      (effects (font (size 1.27 1.27) (thickness 0.15)) (justify left bottom) hide)
    )
    (property "Author" "Antmicro" (at 165.1 124.46 0)
      (effects (font (size 1.27 1.27) (thickness 0.15)) (justify left bottom) hide)
    )
    (property "Voltage" "50V" (at 165.1 127 0)
      (effects (font (size 1.27 1.27)) (justify left bottom) hide)
    )
    (property "Dielectric" "X5R" (at 165.1 129.54 0)
      (effects (font (size 1.27 1.27)) (justify left bottom) hide)
    )
    (pin "1")
    (pin "2")
    (instances
      (project "data-center-rdimm-ddr4-tester"
        (path ""
          (reference "C246") (unit 1)
        )
      )
    )
  )

  (symbol (lib_id "antmicroCapacitors0402:C_100n_0402") (at 249.555 104.14 0) (mirror x) (unit 1)
    (in_bom yes) (on_board yes) (dnp no)
    (property "Reference" "C317" (at 248.285 102.87 0)
      (effects (font (size 1.524 1.524)))
    )
    (property "Value" "C_100n_0402" (at 269.875 93.98 0)
      (effects (font (size 1.27 1.27) (thickness 0.15)) (justify left bottom) hide)
    )
    (property "Footprint" "antmicro-footprints:C_0402_1005Metric" (at 269.875 91.44 0)
      (effects (font (size 1.27 1.27) (thickness 0.15)) (justify left bottom) hide)
    )
    (property "Datasheet" "https://search.murata.co.jp/Ceramy/image/img/A01X/G101/ENG/GRM155R61H104KE14-01.pdf" (at 269.875 88.9 0)
      (effects (font (size 1.27 1.27) (thickness 0.15)) (justify left bottom) hide)
    )
    (property "Manufacturer" "Murata" (at 269.875 83.82 0)
      (effects (font (size 1.27 1.27) (thickness 0.15)) (justify left bottom) hide)
    )
    (property "MPN" "GRM155R61H104KE14D" (at 269.875 86.36 0)
      (effects (font (size 1.27 1.27) (thickness 0.15)) (justify left bottom) hide)
    )
    (property "Val" "100n" (at 255.27 102.87 0)
      (effects (font (size 1.27 1.27) (thickness 0.15)))
    )
    (property "License" "Apache-2.0" (at 269.875 81.28 0)
      (effects (font (size 1.27 1.27) (thickness 0.15)) (justify left bottom) hide)
    )
    (property "Author" "Antmicro" (at 269.875 78.74 0)
      (effects (font (size 1.27 1.27) (thickness 0.15)) (justify left bottom) hide)
    )
    (property "Voltage" "50V" (at 269.875 76.2 0)
      (effects (font (size 1.27 1.27)) (justify left bottom) hide)
    )
    (property "Dielectric" "X5R" (at 269.875 73.66 0)
      (effects (font (size 1.27 1.27)) (justify left bottom) hide)
    )
    (pin "1")
    (pin "2")
    (instances
      (project "data-center-rdimm-ddr4-tester"
        (path ""
          (reference "C317") (unit 1)
        )
      )
    )
  )

  (symbol (lib_id "antmicroCapacitors0402:C_100n_0402") (at 132.08 106.68 0) (unit 1)
    (in_bom yes) (on_board yes) (dnp no)
    (property "Reference" "C198" (at 130.81 105.41 0)
      (effects (font (size 1.524 1.524)))
    )
    (property "Value" "C_100n_0402" (at 152.4 116.84 0)
      (effects (font (size 1.27 1.27) (thickness 0.15)) (justify left bottom) hide)
    )
    (property "Footprint" "antmicro-footprints:C_0402_1005Metric" (at 152.4 119.38 0)
      (effects (font (size 1.27 1.27) (thickness 0.15)) (justify left bottom) hide)
    )
    (property "Datasheet" "https://search.murata.co.jp/Ceramy/image/img/A01X/G101/ENG/GRM155R61H104KE14-01.pdf" (at 152.4 121.92 0)
      (effects (font (size 1.27 1.27) (thickness 0.15)) (justify left bottom) hide)
    )
    (property "Manufacturer" "Murata" (at 152.4 127 0)
      (effects (font (size 1.27 1.27) (thickness 0.15)) (justify left bottom) hide)
    )
    (property "MPN" "GRM155R61H104KE14D" (at 152.4 124.46 0)
      (effects (font (size 1.27 1.27) (thickness 0.15)) (justify left bottom) hide)
    )
    (property "Val" "100n" (at 137.795 105.41 0)
      (effects (font (size 1.27 1.27) (thickness 0.15)))
    )
    (property "License" "Apache-2.0" (at 152.4 129.54 0)
      (effects (font (size 1.27 1.27) (thickness 0.15)) (justify left bottom) hide)
    )
    (property "Author" "Antmicro" (at 152.4 132.08 0)
      (effects (font (size 1.27 1.27) (thickness 0.15)) (justify left bottom) hide)
    )
    (property "Voltage" "50V" (at 152.4 134.62 0)
      (effects (font (size 1.27 1.27)) (justify left bottom) hide)
    )
    (property "Dielectric" "X5R" (at 152.4 137.16 0)
      (effects (font (size 1.27 1.27)) (justify left bottom) hide)
    )
    (pin "1")
    (pin "2")
    (instances
      (project "data-center-rdimm-ddr4-tester"
        (path ""
          (reference "C198") (unit 1)
        )
      )
    )
  )

  (symbol (lib_id "antmicroCapacitors0402:C_100n_0402") (at 144.78 104.14 0) (unit 1)
    (in_bom yes) (on_board yes) (dnp no)
    (property "Reference" "C194" (at 143.51 102.87 0)
      (effects (font (size 1.524 1.524)))
    )
    (property "Value" "C_100n_0402" (at 165.1 114.3 0)
      (effects (font (size 1.27 1.27) (thickness 0.15)) (justify left bottom) hide)
    )
    (property "Footprint" "antmicro-footprints:C_0402_1005Metric" (at 165.1 116.84 0)
      (effects (font (size 1.27 1.27) (thickness 0.15)) (justify left bottom) hide)
    )
    (property "Datasheet" "https://search.murata.co.jp/Ceramy/image/img/A01X/G101/ENG/GRM155R61H104KE14-01.pdf" (at 165.1 119.38 0)
      (effects (font (size 1.27 1.27) (thickness 0.15)) (justify left bottom) hide)
    )
    (property "Manufacturer" "Murata" (at 165.1 124.46 0)
      (effects (font (size 1.27 1.27) (thickness 0.15)) (justify left bottom) hide)
    )
    (property "MPN" "GRM155R61H104KE14D" (at 165.1 121.92 0)
      (effects (font (size 1.27 1.27) (thickness 0.15)) (justify left bottom) hide)
    )
    (property "Val" "100n" (at 150.495 102.87 0)
      (effects (font (size 1.27 1.27) (thickness 0.15)))
    )
    (property "License" "Apache-2.0" (at 165.1 127 0)
      (effects (font (size 1.27 1.27) (thickness 0.15)) (justify left bottom) hide)
    )
    (property "Author" "Antmicro" (at 165.1 129.54 0)
      (effects (font (size 1.27 1.27) (thickness 0.15)) (justify left bottom) hide)
    )
    (property "Voltage" "50V" (at 165.1 132.08 0)
      (effects (font (size 1.27 1.27)) (justify left bottom) hide)
    )
    (property "Dielectric" "X5R" (at 165.1 134.62 0)
      (effects (font (size 1.27 1.27)) (justify left bottom) hide)
    )
    (pin "1")
    (pin "2")
    (instances
      (project "data-center-rdimm-ddr4-tester"
        (path ""
          (reference "C194") (unit 1)
        )
      )
    )
  )

  (symbol (lib_id "antmicroCapacitors0402:C_100n_0402") (at 262.255 101.6 0) (mirror x) (unit 1)
    (in_bom yes) (on_board yes) (dnp no)
    (property "Reference" "C316" (at 260.985 100.33 0)
      (effects (font (size 1.524 1.524)))
    )
    (property "Value" "C_100n_0402" (at 282.575 91.44 0)
      (effects (font (size 1.27 1.27) (thickness 0.15)) (justify left bottom) hide)
    )
    (property "Footprint" "antmicro-footprints:C_0402_1005Metric" (at 282.575 88.9 0)
      (effects (font (size 1.27 1.27) (thickness 0.15)) (justify left bottom) hide)
    )
    (property "Datasheet" "https://search.murata.co.jp/Ceramy/image/img/A01X/G101/ENG/GRM155R61H104KE14-01.pdf" (at 282.575 86.36 0)
      (effects (font (size 1.27 1.27) (thickness 0.15)) (justify left bottom) hide)
    )
    (property "Manufacturer" "Murata" (at 282.575 81.28 0)
      (effects (font (size 1.27 1.27) (thickness 0.15)) (justify left bottom) hide)
    )
    (property "MPN" "GRM155R61H104KE14D" (at 282.575 83.82 0)
      (effects (font (size 1.27 1.27) (thickness 0.15)) (justify left bottom) hide)
    )
    (property "Val" "100n" (at 267.97 100.33 0)
      (effects (font (size 1.27 1.27) (thickness 0.15)))
    )
    (property "License" "Apache-2.0" (at 282.575 78.74 0)
      (effects (font (size 1.27 1.27) (thickness 0.15)) (justify left bottom) hide)
    )
    (property "Author" "Antmicro" (at 282.575 76.2 0)
      (effects (font (size 1.27 1.27) (thickness 0.15)) (justify left bottom) hide)
    )
    (property "Voltage" "50V" (at 282.575 73.66 0)
      (effects (font (size 1.27 1.27)) (justify left bottom) hide)
    )
    (property "Dielectric" "X5R" (at 282.575 71.12 0)
      (effects (font (size 1.27 1.27)) (justify left bottom) hide)
    )
    (pin "1")
    (pin "2")
    (instances
      (project "data-center-rdimm-ddr4-tester"
        (path ""
          (reference "C316") (unit 1)
        )
      )
    )
  )

  (symbol (lib_id "antmicroMicrocontrollers:XC7K160T-FFG676") (at 172.085 53.34 0) (unit 9)
    (in_bom yes) (on_board yes) (dnp no) (fields_autoplaced)
    (property "Reference" "U15" (at 199.39 41.275 0)
      (effects (font (size 1.27 1.27)))
    )
    (property "Value" "XC7K160T-FFG676" (at 199.39 43.815 0)
      (effects (font (size 1.27 1.27) (thickness 0.15)))
    )
    (property "Footprint" "antmicro-footprints:BGA-676_27x27mm_Layout26x26_P1X1mm" (at 240.665 55.88 0)
      (effects (font (size 1.27 1.27) (thickness 0.15)) (justify left bottom) hide)
    )
    (property "Datasheet" "https://docs.xilinx.com/v/u/en-US/ds180_7Series_Overview" (at 240.665 58.42 0)
      (effects (font (size 1.27 1.27) (thickness 0.15)) (justify left bottom) hide)
    )
    (property "MPN" "XC7K160T-FFG676" (at 172.085 53.34 0)
      (effects (font (size 1.27 1.27)) hide)
    )
    (property "Author" "Antmicro" (at 240.665 60.96 0)
      (effects (font (size 1.27 1.27) (thickness 0.15)) (justify left bottom) hide)
    )
    (property "License" "Apache-2.0" (at 240.665 63.5 0)
      (effects (font (size 1.27 1.27) (thickness 0.15)) (justify left bottom) hide)
    )
    (property "Manufacturer" "AMD-Xilinx" (at 172.085 53.34 0)
      (effects (font (size 1.27 1.27)) hide)
    )
    (pin "AA21")
    (pin "AA22")
    (pin "AA23")
    (pin "AA24")
    (pin "AA25")
    (pin "AB21")
    (pin "AB22")
    (pin "AB24")
    (pin "AB25")
    (pin "AB26")
    (pin "AC21")
    (pin "AC22")
    (pin "AC23")
    (pin "AC24")
    (pin "AC25")
    (pin "AC26")
    (pin "AD21")
    (pin "AD22")
    (pin "AD23")
    (pin "AD24")
    (pin "AD25")
    (pin "AD26")
    (pin "AE21")
    (pin "AE22")
    (pin "AE23")
    (pin "AE25")
    (pin "AE26")
    (pin "AF22")
    (pin "AF23")
    (pin "AF24")
    (pin "AF25")
    (pin "AF26")
    (pin "U21")
    (pin "U22")
    (pin "U23")
    (pin "U24")
    (pin "U25")
    (pin "U26")
    (pin "V20")
    (pin "V21")
    (pin "V22")
    (pin "V23")
    (pin "V24")
    (pin "V26")
    (pin "W20")
    (pin "W21")
    (pin "W23")
    (pin "W24")
    (pin "W25")
    (pin "W26")
    (pin "Y20")
    (pin "Y21")
    (pin "Y22")
    (pin "Y23")
    (pin "Y24")
    (pin "Y25")
    (pin "Y26")
    (pin "K24")
    (pin "K25")
    (pin "K26")
    (pin "L24")
    (pin "L25")
    (pin "M19")
    (pin "M20")
    (pin "M21")
    (pin "M22")
    (pin "M24")
    (pin "M25")
    (pin "M26")
    (pin "N16")
    (pin "N17")
    (pin "N18")
    (pin "N19")
    (pin "N21")
    (pin "N22")
    (pin "N23")
    (pin "N24")
    (pin "N25")
    (pin "N26")
    (pin "P16")
    (pin "P18")
    (pin "P19")
    (pin "P20")
    (pin "P21")
    (pin "P22")
    (pin "P23")
    (pin "P24")
    (pin "P25")
    (pin "P26")
    (pin "R16")
    (pin "R17")
    (pin "R18")
    (pin "R19")
    (pin "R20")
    (pin "R21")
    (pin "R22")
    (pin "R23")
    (pin "R25")
    (pin "R26")
    (pin "T16")
    (pin "T17")
    (pin "T18")
    (pin "T19")
    (pin "T20")
    (pin "T22")
    (pin "T23")
    (pin "T24")
    (pin "T25")
    (pin "T26")
    (pin "U16")
    (pin "U17")
    (pin "U19")
    (pin "U20")
    (pin "A20")
    (pin "A21")
    (pin "A22")
    (pin "A23")
    (pin "A24")
    (pin "A25")
    (pin "B20")
    (pin "B21")
    (pin "B22")
    (pin "B24")
    (pin "B25")
    (pin "B26")
    (pin "C21")
    (pin "C22")
    (pin "C23")
    (pin "C24")
    (pin "C25")
    (pin "C26")
    (pin "D21")
    (pin "D22")
    (pin "D23")
    (pin "D24")
    (pin "D25")
    (pin "D26")
    (pin "E21")
    (pin "E22")
    (pin "E23")
    (pin "E25")
    (pin "E26")
    (pin "F22")
    (pin "F23")
    (pin "F24")
    (pin "F25")
    (pin "F26")
    (pin "G21")
    (pin "G22")
    (pin "G23")
    (pin "G24")
    (pin "G25")
    (pin "G26")
    (pin "H21")
    (pin "H22")
    (pin "H23")
    (pin "H24")
    (pin "H26")
    (pin "J21")
    (pin "J23")
    (pin "J24")
    (pin "J25")
    (pin "J26")
    (pin "K21")
    (pin "K22")
    (pin "K23")
    (pin "L21")
    (pin "L22")
    (pin "L23")
    (pin "A17")
    (pin "A18")
    (pin "A19")
    (pin "B16")
    (pin "B17")
    (pin "B18")
    (pin "B19")
    (pin "C16")
    (pin "C17")
    (pin "C18")
    (pin "C19")
    (pin "D15")
    (pin "D16")
    (pin "D18")
    (pin "D19")
    (pin "D20")
    (pin "E15")
    (pin "E16")
    (pin "E17")
    (pin "E18")
    (pin "E19")
    (pin "E20")
    (pin "F15")
    (pin "F16")
    (pin "F17")
    (pin "F18")
    (pin "F19")
    (pin "F20")
    (pin "G15")
    (pin "G16")
    (pin "G17")
    (pin "G19")
    (pin "G20")
    (pin "H16")
    (pin "H17")
    (pin "H18")
    (pin "H19")
    (pin "H20")
    (pin "J15")
    (pin "J16")
    (pin "J17")
    (pin "J18")
    (pin "J19")
    (pin "J20")
    (pin "K15")
    (pin "K16")
    (pin "K17")
    (pin "K18")
    (pin "K20")
    (pin "L17")
    (pin "L18")
    (pin "L19")
    (pin "L20")
    (pin "M16")
    (pin "M17")
    (pin "M18")
    (pin "A10")
    (pin "A11")
    (pin "A12")
    (pin "A13")
    (pin "A14")
    (pin "A15")
    (pin "A8")
    (pin "A9")
    (pin "B10")
    (pin "B11")
    (pin "B12")
    (pin "B14")
    (pin "B15")
    (pin "B8")
    (pin "B9")
    (pin "C11")
    (pin "C12")
    (pin "C13")
    (pin "C14")
    (pin "C15")
    (pin "C9")
    (pin "D10")
    (pin "D11")
    (pin "D12")
    (pin "D13")
    (pin "D14")
    (pin "D8")
    (pin "D9")
    (pin "E10")
    (pin "E11")
    (pin "E12")
    (pin "E13")
    (pin "E9")
    (pin "F10")
    (pin "F12")
    (pin "F13")
    (pin "F14")
    (pin "F8")
    (pin "F9")
    (pin "G10")
    (pin "G11")
    (pin "G12")
    (pin "G13")
    (pin "G14")
    (pin "G9")
    (pin "H10")
    (pin "H11")
    (pin "H12")
    (pin "H13")
    (pin "H14")
    (pin "H8")
    (pin "H9")
    (pin "J10")
    (pin "J11")
    (pin "J13")
    (pin "J14")
    (pin "J8")
    (pin "AA14")
    (pin "AA15")
    (pin "AA17")
    (pin "AA18")
    (pin "AA19")
    (pin "AA20")
    (pin "AB14")
    (pin "AB15")
    (pin "AB16")
    (pin "AB17")
    (pin "AB18")
    (pin "AB19")
    (pin "AB20")
    (pin "AC14")
    (pin "AC15")
    (pin "AC16")
    (pin "AC17")
    (pin "AC18")
    (pin "AC19")
    (pin "AD14")
    (pin "AD15")
    (pin "AD16")
    (pin "AD18")
    (pin "AD19")
    (pin "AD20")
    (pin "AE15")
    (pin "AE16")
    (pin "AE17")
    (pin "AE18")
    (pin "AE19")
    (pin "AE20")
    (pin "AF14")
    (pin "AF15")
    (pin "AF16")
    (pin "AF17")
    (pin "AF18")
    (pin "AF19")
    (pin "AF20")
    (pin "V13")
    (pin "V14")
    (pin "V16")
    (pin "V17")
    (pin "V18")
    (pin "V19")
    (pin "W13")
    (pin "W14")
    (pin "W15")
    (pin "W16")
    (pin "W17")
    (pin "W18")
    (pin "W19")
    (pin "Y14")
    (pin "Y15")
    (pin "Y16")
    (pin "Y17")
    (pin "Y18")
    (pin "AA10")
    (pin "AA11")
    (pin "AA12")
    (pin "AA13")
    (pin "AA7")
    (pin "AA8")
    (pin "AA9")
    (pin "AB10")
    (pin "AB11")
    (pin "AB12")
    (pin "AB7")
    (pin "AB8")
    (pin "AB9")
    (pin "AC11")
    (pin "AC12")
    (pin "AC13")
    (pin "AC7")
    (pin "AC8")
    (pin "AC9")
    (pin "AD10")
    (pin "AD11")
    (pin "AD12")
    (pin "AD13")
    (pin "AD8")
    (pin "AD9")
    (pin "AE10")
    (pin "AE11")
    (pin "AE12")
    (pin "AE13")
    (pin "AE7")
    (pin "AE8")
    (pin "AE9")
    (pin "AF10")
    (pin "AF12")
    (pin "AF13")
    (pin "AF7")
    (pin "AF8")
    (pin "AF9")
    (pin "U9")
    (pin "V10")
    (pin "V11")
    (pin "V12")
    (pin "V7")
    (pin "V8")
    (pin "V9")
    (pin "W10")
    (pin "W11")
    (pin "W7")
    (pin "W8")
    (pin "W9")
    (pin "Y10")
    (pin "Y11")
    (pin "Y12")
    (pin "Y13")
    (pin "Y7")
    (pin "Y8")
    (pin "AA1")
    (pin "AA2")
    (pin "AA3")
    (pin "AA4")
    (pin "AA5")
    (pin "AB1")
    (pin "AB2")
    (pin "AB4")
    (pin "AB5")
    (pin "AB6")
    (pin "AC1")
    (pin "AC2")
    (pin "AC3")
    (pin "AC4")
    (pin "AC5")
    (pin "AC6")
    (pin "AD1")
    (pin "AD2")
    (pin "AD3")
    (pin "AD4")
    (pin "AD5")
    (pin "AD6")
    (pin "AE1")
    (pin "AE2")
    (pin "AE3")
    (pin "AE5")
    (pin "AE6")
    (pin "AF2")
    (pin "AF3")
    (pin "AF4")
    (pin "AF5")
    (pin "AF6")
    (pin "T7")
    (pin "U1")
    (pin "U2")
    (pin "U3")
    (pin "U4")
    (pin "U5")
    (pin "U6")
    (pin "U7")
    (pin "V1")
    (pin "V2")
    (pin "V3")
    (pin "V4")
    (pin "V6")
    (pin "W1")
    (pin "W3")
    (pin "W4")
    (pin "W5")
    (pin "W6")
    (pin "Y1")
    (pin "Y2")
    (pin "Y3")
    (pin "Y4")
    (pin "Y5")
    (pin "Y6")
    (pin "A3")
    (pin "A4")
    (pin "B1")
    (pin "B2")
    (pin "B5")
    (pin "B6")
    (pin "C3")
    (pin "C4")
    (pin "D1")
    (pin "D2")
    (pin "D5")
    (pin "D6")
    (pin "E3")
    (pin "E4")
    (pin "F1")
    (pin "F2")
    (pin "F5")
    (pin "F6")
    (pin "G3")
    (pin "G4")
    (pin "H1")
    (pin "H2")
    (pin "H5")
    (pin "H6")
    (pin "J3")
    (pin "J4")
    (pin "K1")
    (pin "K2")
    (pin "K5")
    (pin "K6")
    (pin "L3")
    (pin "L4")
    (pin "M1")
    (pin "M2")
    (pin "N3")
    (pin "N4")
    (pin "P1")
    (pin "P2")
    (pin "R3")
    (pin "R4")
    (pin "A1")
    (pin "A16")
    (pin "A2")
    (pin "A26")
    (pin "A5")
    (pin "A6")
    (pin "A7")
    (pin "AA16")
    (pin "AA26")
    (pin "AA6")
    (pin "AB13")
    (pin "AB23")
    (pin "AB3")
    (pin "AC10")
    (pin "AC20")
    (pin "AD17")
    (pin "AD7")
    (pin "AE14")
    (pin "AE24")
    (pin "AE4")
    (pin "AF1")
    (pin "AF11")
    (pin "AF21")
    (pin "B13")
    (pin "B23")
    (pin "B3")
    (pin "B4")
    (pin "B7")
    (pin "C1")
    (pin "C10")
    (pin "C2")
    (pin "C20")
    (pin "C5")
    (pin "C6")
    (pin "C7")
    (pin "D17")
    (pin "D3")
    (pin "D4")
    (pin "D7")
    (pin "E1")
    (pin "E14")
    (pin "E2")
    (pin "E24")
    (pin "E5")
    (pin "E6")
    (pin "E7")
    (pin "E8")
    (pin "F11")
    (pin "F21")
    (pin "F3")
    (pin "F4")
    (pin "F7")
    (pin "G1")
    (pin "G18")
    (pin "G2")
    (pin "G5")
    (pin "G6")
    (pin "G8")
    (pin "H15")
    (pin "H25")
    (pin "H3")
    (pin "H4")
    (pin "H7")
    (pin "J1")
    (pin "J12")
    (pin "J2")
    (pin "J22")
    (pin "J5")
    (pin "J6")
    (pin "J9")
    (pin "K10")
    (pin "K11")
    (pin "K12")
    (pin "K13")
    (pin "K14")
    (pin "K19")
    (pin "K3")
    (pin "K4")
    (pin "K7")
    (pin "K8")
    (pin "K9")
    (pin "L1")
    (pin "L10")
    (pin "L11")
    (pin "L12")
    (pin "L13")
    (pin "L14")
    (pin "L15")
    (pin "L16")
    (pin "L2")
    (pin "L26")
    (pin "L5")
    (pin "L6")
    (pin "L9")
    (pin "M10")
    (pin "M11")
    (pin "M12")
    (pin "M13")
    (pin "M14")
    (pin "M15")
    (pin "M23")
    (pin "M3")
    (pin "M4")
    (pin "M5")
    (pin "M6")
    (pin "M7")
    (pin "M8")
    (pin "M9")
    (pin "N1")
    (pin "N10")
    (pin "N13")
    (pin "N14")
    (pin "N15")
    (pin "N2")
    (pin "N20")
    (pin "N5")
    (pin "N6")
    (pin "N7")
    (pin "N9")
    (pin "P10")
    (pin "P13")
    (pin "P14")
    (pin "P15")
    (pin "P17")
    (pin "P3")
    (pin "P4")
    (pin "P8")
    (pin "P9")
    (pin "R1")
    (pin "R10")
    (pin "R13")
    (pin "R14")
    (pin "R15")
    (pin "R2")
    (pin "R24")
    (pin "R5")
    (pin "R8")
    (pin "R9")
    (pin "T1")
    (pin "T10")
    (pin "T11")
    (pin "T12")
    (pin "T13")
    (pin "T14")
    (pin "T15")
    (pin "T21")
    (pin "T3")
    (pin "T4")
    (pin "T8")
    (pin "T9")
    (pin "U10")
    (pin "U11")
    (pin "U12")
    (pin "U13")
    (pin "U14")
    (pin "U15")
    (pin "U18")
    (pin "U8")
    (pin "V15")
    (pin "V25")
    (pin "V5")
    (pin "W12")
    (pin "W2")
    (pin "W22")
    (pin "Y19")
    (pin "Y9")
    (pin "C8")
    (pin "G7")
    (pin "J7")
    (pin "L7")
    (pin "L8")
    (pin "N11")
    (pin "N12")
    (pin "N8")
    (pin "P11")
    (pin "P12")
    (pin "P5")
    (pin "P6")
    (pin "P7")
    (pin "R11")
    (pin "R12")
    (pin "R6")
    (pin "R7")
    (pin "T2")
    (pin "T5")
    (pin "T6")
    (instances
      (project "data-center-rdimm-ddr4-tester"
        (path ""
          (reference "U15") (unit 9)
        )
      )
    )
  )

  (symbol (lib_id "antmicroCapacitors0402:C_100n_0402") (at 262.255 106.68 0) (mirror x) (unit 1)
    (in_bom yes) (on_board yes) (dnp no)
    (property "Reference" "C318" (at 260.985 105.41 0)
      (effects (font (size 1.524 1.524)))
    )
    (property "Value" "C_100n_0402" (at 282.575 96.52 0)
      (effects (font (size 1.27 1.27) (thickness 0.15)) (justify left bottom) hide)
    )
    (property "Footprint" "antmicro-footprints:C_0402_1005Metric" (at 282.575 93.98 0)
      (effects (font (size 1.27 1.27) (thickness 0.15)) (justify left bottom) hide)
    )
    (property "Datasheet" "https://search.murata.co.jp/Ceramy/image/img/A01X/G101/ENG/GRM155R61H104KE14-01.pdf" (at 282.575 91.44 0)
      (effects (font (size 1.27 1.27) (thickness 0.15)) (justify left bottom) hide)
    )
    (property "Manufacturer" "Murata" (at 282.575 86.36 0)
      (effects (font (size 1.27 1.27) (thickness 0.15)) (justify left bottom) hide)
    )
    (property "MPN" "GRM155R61H104KE14D" (at 282.575 88.9 0)
      (effects (font (size 1.27 1.27) (thickness 0.15)) (justify left bottom) hide)
    )
    (property "Val" "100n" (at 267.97 105.41 0)
      (effects (font (size 1.27 1.27) (thickness 0.15)))
    )
    (property "License" "Apache-2.0" (at 282.575 83.82 0)
      (effects (font (size 1.27 1.27) (thickness 0.15)) (justify left bottom) hide)
    )
    (property "Author" "Antmicro" (at 282.575 81.28 0)
      (effects (font (size 1.27 1.27) (thickness 0.15)) (justify left bottom) hide)
    )
    (property "Voltage" "50V" (at 282.575 78.74 0)
      (effects (font (size 1.27 1.27)) (justify left bottom) hide)
    )
    (property "Dielectric" "X5R" (at 282.575 76.2 0)
      (effects (font (size 1.27 1.27)) (justify left bottom) hide)
    )
    (pin "1")
    (pin "2")
    (instances
      (project "data-center-rdimm-ddr4-tester"
        (path ""
          (reference "C318") (unit 1)
        )
      )
    )
  )

  (symbol (lib_id "antmicroCapacitors0402:C_100n_0402") (at 132.08 101.6 0) (unit 1)
    (in_bom yes) (on_board yes) (dnp no)
    (property "Reference" "C247" (at 130.81 100.33 0)
      (effects (font (size 1.524 1.524)))
    )
    (property "Value" "C_100n_0402" (at 152.4 111.76 0)
      (effects (font (size 1.27 1.27) (thickness 0.15)) (justify left bottom) hide)
    )
    (property "Footprint" "antmicro-footprints:C_0402_1005Metric" (at 152.4 114.3 0)
      (effects (font (size 1.27 1.27) (thickness 0.15)) (justify left bottom) hide)
    )
    (property "Datasheet" "https://search.murata.co.jp/Ceramy/image/img/A01X/G101/ENG/GRM155R61H104KE14-01.pdf" (at 152.4 116.84 0)
      (effects (font (size 1.27 1.27) (thickness 0.15)) (justify left bottom) hide)
    )
    (property "Manufacturer" "Murata" (at 152.4 121.92 0)
      (effects (font (size 1.27 1.27) (thickness 0.15)) (justify left bottom) hide)
    )
    (property "MPN" "GRM155R61H104KE14D" (at 152.4 119.38 0)
      (effects (font (size 1.27 1.27) (thickness 0.15)) (justify left bottom) hide)
    )
    (property "Val" "100n" (at 137.795 100.33 0)
      (effects (font (size 1.27 1.27) (thickness 0.15)))
    )
    (property "License" "Apache-2.0" (at 152.4 124.46 0)
      (effects (font (size 1.27 1.27) (thickness 0.15)) (justify left bottom) hide)
    )
    (property "Author" "Antmicro" (at 152.4 127 0)
      (effects (font (size 1.27 1.27) (thickness 0.15)) (justify left bottom) hide)
    )
    (property "Voltage" "50V" (at 152.4 129.54 0)
      (effects (font (size 1.27 1.27)) (justify left bottom) hide)
    )
    (property "Dielectric" "X5R" (at 152.4 132.08 0)
      (effects (font (size 1.27 1.27)) (justify left bottom) hide)
    )
    (pin "1")
    (pin "2")
    (instances
      (project "data-center-rdimm-ddr4-tester"
        (path ""
          (reference "C247") (unit 1)
        )
      )
    )
  )

  (symbol (lib_id "antmicroCapacitors0402:C_100n_0402") (at 249.555 99.06 0) (mirror x) (unit 1)
    (in_bom yes) (on_board yes) (dnp no)
    (property "Reference" "C315" (at 248.285 97.79 0)
      (effects (font (size 1.524 1.524)))
    )
    (property "Value" "C_100n_0402" (at 269.875 88.9 0)
      (effects (font (size 1.27 1.27) (thickness 0.15)) (justify left bottom) hide)
    )
    (property "Footprint" "antmicro-footprints:C_0402_1005Metric" (at 269.875 86.36 0)
      (effects (font (size 1.27 1.27) (thickness 0.15)) (justify left bottom) hide)
    )
    (property "Datasheet" "https://search.murata.co.jp/Ceramy/image/img/A01X/G101/ENG/GRM155R61H104KE14-01.pdf" (at 269.875 83.82 0)
      (effects (font (size 1.27 1.27) (thickness 0.15)) (justify left bottom) hide)
    )
    (property "Manufacturer" "Murata" (at 269.875 78.74 0)
      (effects (font (size 1.27 1.27) (thickness 0.15)) (justify left bottom) hide)
    )
    (property "MPN" "GRM155R61H104KE14D" (at 269.875 81.28 0)
      (effects (font (size 1.27 1.27) (thickness 0.15)) (justify left bottom) hide)
    )
    (property "Val" "100n" (at 255.27 97.79 0)
      (effects (font (size 1.27 1.27) (thickness 0.15)))
    )
    (property "License" "Apache-2.0" (at 269.875 76.2 0)
      (effects (font (size 1.27 1.27) (thickness 0.15)) (justify left bottom) hide)
    )
    (property "Author" "Antmicro" (at 269.875 73.66 0)
      (effects (font (size 1.27 1.27) (thickness 0.15)) (justify left bottom) hide)
    )
    (property "Voltage" "50V" (at 269.875 71.12 0)
      (effects (font (size 1.27 1.27)) (justify left bottom) hide)
    )
    (property "Dielectric" "X5R" (at 269.875 68.58 0)
      (effects (font (size 1.27 1.27)) (justify left bottom) hide)
    )
    (pin "1")
    (pin "2")
    (instances
      (project "data-center-rdimm-ddr4-tester"
        (path ""
          (reference "C315") (unit 1)
        )
      )
    )
  )
)
